(kicad_pcb
	(version 20241229)
	(generator "pcbnew")
	(generator_version "9.0")
	(general
		(thickness 1.62)
		(legacy_teardrops no)
	)
	(paper "A4")
	(title_block
		(title "OCuLink to 10GbE adapter")
		(date "2026-02-23")
		(rev "1.1.0")
		(company "Antmicro Ltd")
		(comment 1 "www.antmicro.com")
		(comment 9 "footprints 36-41 of 510")
	)
	(layers
		(0 "F.Cu" signal)
		(4 "In1.Cu" signal)
		(6 "In2.Cu" signal)
		(8 "In3.Cu" signal)
		(10 "In4.Cu" signal)
		(12 "In5.Cu" signal)
		(14 "In6.Cu" signal)
		(2 "B.Cu" signal)
		(9 "F.Adhes" user "F.Adhesive")
		(11 "B.Adhes" user "B.Adhesive")
		(13 "F.Paste" user)
		(15 "B.Paste" user)
		(5 "F.SilkS" user "F.Silkscreen")
		(7 "B.SilkS" user "B.Silkscreen")
		(1 "F.Mask" user)
		(3 "B.Mask" user)
		(17 "Dwgs.User" user "User.Drawings")
		(19 "Cmts.User" user "User.Comments")
		(21 "Eco1.User" user "User.Eco1")
		(23 "Eco2.User" user "User.Eco2")
		(25 "Edge.Cuts" user)
		(27 "Margin" user)
		(31 "F.CrtYd" user "F.Courtyard")
		(29 "B.CrtYd" user "B.Courtyard")
		(35 "F.Fab" user)
		(33 "B.Fab" user)
	)
	(footprint "antmicro-footprints:C_0603_1608Metric_EIA"
		(layer "F.Cu")
		(at 51.900001 88.500001 -90)
		(descr "Capacitor SMD 0603, IPC-7351 Density Level A")
		(tags "Capacitor 0603")
		(property "Reference" "C12"
			(at 1.239999 0.950001 90)
			(layer "F.SilkS")
			(effects
				(font
					(size 0.7 0.7)
					(thickness 0.15)
				)
				(justify right top)
			)
		)
		(property "Value" "C_22u_16V_0603"
			(at -1.42757 1.770288 90)
			(layer "F.Fab")
			(hide yes)
			(effects
				(font
					(size 0.7 0.7)
					(thickness 0.15)
				)
				(justify right top)
			)
		)
		(property "Datasheet" "https://product.samsungsem.com/mlcc/CL10A226MO7JZN.do"
			(at 0 0 90)
			(layer "F.Fab")
			(hide yes)
			(effects
				(font
					(size 1.27 1.27)
					(thickness 0.15)
				)
			)
		)
		(property "Description" "SMD Multilayer Ceramic Capacitor"
			(at 0 0 90)
			(layer "F.Fab")
			(hide yes)
			(effects
				(font
					(size 1.27 1.27)
					(thickness 0.15)
				)
			)
		)
		(property "MPN" "CL10A226MO7JZNC"
			(at 0 0 270)
			(unlocked yes)
			(layer "F.Fab")
			(hide yes)
			(effects
				(font
					(size 1 1)
					(thickness 0.15)
				)
			)
		)
		(property "Manufacturer" "Samsung Electro-Mechanics"
			(at 0 0 270)
			(unlocked yes)
			(layer "F.Fab")
			(hide yes)
			(effects
				(font
					(size 1 1)
					(thickness 0.15)
				)
			)
		)
		(property "License" "Apache-2.0"
			(at 0 0 270)
			(unlocked yes)
			(layer "F.Fab")
			(hide yes)
			(effects
				(font
					(size 1 1)
					(thickness 0.15)
				)
			)
		)
		(property "Author" "Antmicro"
			(at 0 0 270)
			(unlocked yes)
			(layer "F.Fab")
			(hide yes)
			(effects
				(font
					(size 1 1)
					(thickness 0.15)
				)
			)
		)
		(property "Val" "22u"
			(at 0 0 270)
			(unlocked yes)
			(layer "F.Fab")
			(hide yes)
			(effects
				(font
					(size 1 1)
					(thickness 0.15)
				)
			)
		)
		(property "Voltage" "16V"
			(at 0 0 270)
			(unlocked yes)
			(layer "F.Fab")
			(hide yes)
			(effects
				(font
					(size 1 1)
					(thickness 0.15)
				)
			)
		)
		(property "Dielectric" ""
			(at 0 0 270)
			(unlocked yes)
			(layer "F.Fab")
			(hide yes)
			(effects
				(font
					(size 1 1)
					(thickness 0.15)
				)
			)
		)
		(property "Public" "False"
			(at 0 0 270)
			(unlocked yes)
			(layer "F.Fab")
			(hide yes)
			(effects
				(font
					(size 1 1)
					(thickness 0.15)
				)
			)
		)
		(sheetname "/Power/")
		(sheetfile "power.kicad_sch")
		(attr smd)
		(fp_line
			(start -0.15 0.55)
			(end 0.15 0.55)
			(stroke
				(width 0.15)
				(type solid)
			)
			(layer "F.SilkS")
		)
		(fp_line
			(start -0.15 -0.55)
			(end 0.15 -0.55)
			(stroke
				(width 0.15)
				(type solid)
			)
			(layer "F.SilkS")
		)
		(fp_rect
			(start -1.25 -0.65)
			(end 1.25 0.65)
			(stroke
				(width 0.05)
				(type solid)
			)
			(fill no)
			(layer "F.CrtYd")
		)
		(fp_rect
			(start -0.8 -0.45)
			(end 0.8 0.45)
			(stroke
				(width 0.15)
				(type solid)
			)
			(fill no)
			(layer "F.Fab")
		)
		(pad "1" smd roundrect
			(at -0.7 0 270)
			(size 0.8 1.1)
			(layers "F.Cu" "F.Mask" "F.Paste")
			(roundrect_rratio 0.2)
			(net 28 "GND")
			(pintype "passive")
		)
		(pad "2" smd roundrect
			(at 0.7 0 270)
			(size 0.8 1.1)
			(layers "F.Cu" "F.Mask" "F.Paste")
			(roundrect_rratio 0.2)
			(net 314 "VCC")
			(pintype "passive")
		)
	)
	(footprint "antmicro-footprints:R_0402_1005Metric"
		(layer "F.Cu")
		(at 104.625001 95.35 90)
		(descr "Resistor SMD 0402")
		(tags "resistor SMD 0402")
		(property "Reference" "R115"
			(at 0.85 -0.525001 90)
			(layer "F.SilkS")
			(effects
				(font
					(size 0.7 0.7)
					(thickness 0.15)
				)
				(justify right bottom)
			)
		)
		(property "Value" "R_2k_0402"
			(at -1.011843 1.772046 90)
			(layer "F.Fab")
			(hide yes)
			(effects
				(font
					(size 0.7 0.7)
					(thickness 0.15)
				)
				(justify left bottom)
			)
		)
		(property "Datasheet" "https://www.bourns.com/docs/product-datasheets/cr.pdf"
			(at 0 0 90)
			(layer "F.Fab")
			(hide yes)
			(effects
				(font
					(size 1.27 1.27)
					(thickness 0.15)
				)
			)
		)
		(property "Description" "SMD Chip Resistor, 2 kohm, ± 1%, 62.5 mW, 0402 [1005 Metric], Thick Film, General Purpose"
			(at 0 0 90)
			(layer "F.Fab")
			(hide yes)
			(effects
				(font
					(size 1.27 1.27)
					(thickness 0.15)
				)
			)
		)
		(property "MPN" "CR0402-FX-2001GLF"
			(at 0 0 90)
			(unlocked yes)
			(layer "F.Fab")
			(hide yes)
			(effects
				(font
					(size 1 1)
					(thickness 0.15)
				)
			)
		)
		(property "Manufacturer" "Bourns"
			(at 0 0 90)
			(unlocked yes)
			(layer "F.Fab")
			(hide yes)
			(effects
				(font
					(size 1 1)
					(thickness 0.15)
				)
			)
		)
		(property "License" "Apache-2.0"
			(at 0 0 90)
			(unlocked yes)
			(layer "F.Fab")
			(hide yes)
			(effects
				(font
					(size 1 1)
					(thickness 0.15)
				)
			)
		)
		(property "Author" "Antmicro"
			(at 0 0 90)
			(unlocked yes)
			(layer "F.Fab")
			(hide yes)
			(effects
				(font
					(size 1 1)
					(thickness 0.15)
				)
			)
		)
		(property "Val" "2k"
			(at 0 0 90)
			(unlocked yes)
			(layer "F.Fab")
			(hide yes)
			(effects
				(font
					(size 1 1)
					(thickness 0.15)
				)
			)
		)
		(property "Tolerance" "1%"
			(at 0 0 90)
			(unlocked yes)
			(layer "F.Fab")
			(hide yes)
			(effects
				(font
					(size 1 1)
					(thickness 0.15)
				)
			)
		)
		(sheetname "/X710-AT2 Misc/")
		(sheetfile "x710-at2-mics.kicad_sch")
		(attr smd)
		(fp_rect
			(start -0.925 -0.47)
			(end 0.925 0.47)
			(stroke
				(width 0.05)
				(type default)
			)
			(fill no)
			(layer "F.CrtYd")
		)
		(fp_rect
			(start -0.5 -0.25)
			(end 0.5 0.25)
			(stroke
				(width 0.15)
				(type solid)
			)
			(fill no)
			(layer "F.Fab")
		)
		(pad "1" smd roundrect
			(at -0.48 0 90)
			(size 0.59 0.64)
			(layers "F.Cu" "F.Mask" "F.Paste")
			(roundrect_rratio 0.25)
			(net 382 "/X710-AT2 Misc/MDIO.MDC")
			(pintype "passive")
		)
		(pad "2" smd roundrect
			(at 0.48 0 90)
			(size 0.59 0.64)
			(layers "F.Cu" "F.Mask" "F.Paste")
			(roundrect_rratio 0.25)
			(net 18 "+1V88")
			(pintype "passive")
		)
	)
	(footprint "antmicro-footprints:C_0402_1005Metric"
		(layer "F.Cu")
		(at 55.100001 85.149999 90)
		(descr "Capacitor SMD 0402")
		(tags "capacitor SMD 0402")
		(property "Reference" "C11"
			(at -1.140001 -2.310001 90)
			(layer "F.SilkS")
			(effects
				(font
					(size 0.7 0.7)
					(thickness 0.15)
				)
				(justify left bottom)
			)
		)
		(property "Value" "C_33p_0402"
			(at -1.022927 2.155213 90)
			(layer "F.Fab")
			(hide yes)
			(effects
				(font
					(size 0.7 0.7)
					(thickness 0.15)
				)
				(justify left bottom)
			)
		)
		(property "Datasheet" "https://spicat.kyocera-avx.com/product/mlcc/chartview/04025A330FAT2A/"
			(at 0 0 90)
			(layer "F.Fab")
			(hide yes)
			(effects
				(font
					(size 1.27 1.27)
					(thickness 0.15)
				)
			)
		)
		(property "Description" "SMD Multilayer Ceramic Capacitor, 33 pF, 50 V, 0402 [1005 Metric], ± 5%, C0G / NP0, MC"
			(at 0 0 90)
			(layer "F.Fab")
			(hide yes)
			(effects
				(font
					(size 1.27 1.27)
					(thickness 0.15)
				)
			)
		)
		(property "MPN" "04025A330FAT2A"
			(at 0 0 90)
			(unlocked yes)
			(layer "F.Fab")
			(hide yes)
			(effects
				(font
					(size 1 1)
					(thickness 0.15)
				)
			)
		)
		(property "Manufacturer" "KYOCERA AVX"
			(at 0 0 90)
			(unlocked yes)
			(layer "F.Fab")
			(hide yes)
			(effects
				(font
					(size 1 1)
					(thickness 0.15)
				)
			)
		)
		(property "License" "Apache-2.0"
			(at 0 0 90)
			(unlocked yes)
			(layer "F.Fab")
			(hide yes)
			(effects
				(font
					(size 1 1)
					(thickness 0.15)
				)
			)
		)
		(property "Author" "Antmicro"
			(at 0 0 90)
			(unlocked yes)
			(layer "F.Fab")
			(hide yes)
			(effects
				(font
					(size 1 1)
					(thickness 0.15)
				)
			)
		)
		(property "Val" "33p"
			(at 0 0 90)
			(unlocked yes)
			(layer "F.Fab")
			(hide yes)
			(effects
				(font
					(size 1 1)
					(thickness 0.15)
				)
			)
		)
		(property "Voltage" ""
			(at 0 0 90)
			(unlocked yes)
			(layer "F.Fab")
			(hide yes)
			(effects
				(font
					(size 1 1)
					(thickness 0.15)
				)
			)
		)
		(property "Dielectric" ""
			(at 0 0 90)
			(unlocked yes)
			(layer "F.Fab")
			(hide yes)
			(effects
				(font
					(size 1 1)
					(thickness 0.15)
				)
			)
		)
		(sheetname "/Power/")
		(sheetfile "power.kicad_sch")
		(attr smd exclude_from_pos_files exclude_from_bom dnp)
		(fp_rect
			(start -0.925 -0.47)
			(end 0.925 0.47)
			(stroke
				(width 0.05)
				(type default)
			)
			(fill no)
			(layer "F.CrtYd")
		)
		(fp_line
			(start 0.504 -0.25)
			(end 0.504 0.248)
			(stroke
				(width 0.15)
				(type solid)
			)
			(layer "F.Fab")
		)
		(fp_line
			(start -0.494 -0.25)
			(end 0.504 -0.25)
			(stroke
				(width 0.15)
				(type solid)
			)
			(layer "F.Fab")
		)
		(fp_line
			(start 0.504 0.248)
			(end -0.494 0.248)
			(stroke
				(width 0.15)
				(type solid)
			)
			(layer "F.Fab")
		)
		(fp_line
			(start -0.494 0.248)
			(end -0.494 -0.25)
			(stroke
				(width 0.15)
				(type solid)
			)
			(layer "F.Fab")
		)
		(pad "1" smd roundrect
			(at -0.48 0 90)
			(size 0.59 0.64)
			(layers "F.Cu" "F.Mask" "F.Paste")
			(roundrect_rratio 0.25)
			(net 329 "/Power/VCCD_FB")
			(pintype "passive")
		)
		(pad "2" smd roundrect
			(at 0.48 0 90)
			(size 0.59 0.64)
			(layers "F.Cu" "F.Mask" "F.Paste")
			(roundrect_rratio 0.25)
			(net 303 "/Power/+VCCD_OUT")
			(pintype "passive")
		)
	)
	(footprint "antmicro-footprints:C_0402_1005Metric"
		(layer "F.Cu")
		(at 57.099998 100.550002 -90)
		(descr "Capacitor SMD 0402")
		(tags "capacitor SMD 0402")
		(property "Reference" "C24"
			(at 0.819998 -0.710002 180)
			(layer "F.SilkS")
			(effects
				(font
					(size 0.7 0.7)
					(thickness 0.12)
					(bold yes)
				)
				(justify right top)
			)
		)
		(property "Value" "C_1u_25V_0402"
			(at -1.022927 2.155213 90)
			(layer "F.Fab")
			(hide yes)
			(effects
				(font
					(size 0.7 0.7)
					(thickness 0.15)
				)
				(justify right top)
			)
		)
		(property "Datasheet" "https://www.murata.com/products/productdetail?partno=GRM155R61E105KE11%23"
			(at 0 0 90)
			(layer "F.Fab")
			(hide yes)
			(effects
				(font
					(size 1.27 1.27)
					(thickness 0.15)
				)
			)
		)
		(property "Description" "SMD Multilayer Ceramic Capacitor, 1 µF, 25 V, 0402 [1005 Metric], ± 10%, X5R, GRM Series"
			(at 0 0 90)
			(layer "F.Fab")
			(hide yes)
			(effects
				(font
					(size 1.27 1.27)
					(thickness 0.15)
				)
			)
		)
		(property "MPN" "GRM155R61E105KE11J"
			(at 0 0 270)
			(unlocked yes)
			(layer "F.Fab")
			(hide yes)
			(effects
				(font
					(size 1 1)
					(thickness 0.15)
				)
			)
		)
		(property "Manufacturer" "Murata"
			(at 0 0 270)
			(unlocked yes)
			(layer "F.Fab")
			(hide yes)
			(effects
				(font
					(size 1 1)
					(thickness 0.15)
				)
			)
		)
		(property "License" "Apache-2.0"
			(at 0 0 270)
			(unlocked yes)
			(layer "F.Fab")
			(hide yes)
			(effects
				(font
					(size 1 1)
					(thickness 0.15)
				)
			)
		)
		(property "Author" "Antmicro"
			(at 0 0 270)
			(unlocked yes)
			(layer "F.Fab")
			(hide yes)
			(effects
				(font
					(size 1 1)
					(thickness 0.15)
				)
			)
		)
		(property "Val" "1u"
			(at 0 0 270)
			(unlocked yes)
			(layer "F.Fab")
			(hide yes)
			(effects
				(font
					(size 1 1)
					(thickness 0.15)
				)
			)
		)
		(property "Voltage" "25V"
			(at 0 0 270)
			(unlocked yes)
			(layer "F.Fab")
			(hide yes)
			(effects
				(font
					(size 1 1)
					(thickness 0.15)
				)
			)
		)
		(property "Dielectric" "X5R"
			(at 0 0 270)
			(unlocked yes)
			(layer "F.Fab")
			(hide yes)
			(effects
				(font
					(size 1 1)
					(thickness 0.15)
				)
			)
		)
		(sheetname "/Power/")
		(sheetfile "power.kicad_sch")
		(attr smd)
		(fp_rect
			(start -0.925 -0.47)
			(end 0.925 0.47)
			(stroke
				(width 0.05)
				(type default)
			)
			(fill no)
			(layer "F.CrtYd")
		)
		(fp_line
			(start -0.494 0.248)
			(end -0.494 -0.25)
			(stroke
				(width 0.15)
				(type solid)
			)
			(layer "F.Fab")
		)
		(fp_line
			(start 0.504 0.248)
			(end -0.494 0.248)
			(stroke
				(width 0.15)
				(type solid)
			)
			(layer "F.Fab")
		)
		(fp_line
			(start -0.494 -0.25)
			(end 0.504 -0.25)
			(stroke
				(width 0.15)
				(type solid)
			)
			(layer "F.Fab")
		)
		(fp_line
			(start 0.504 -0.25)
			(end 0.504 0.248)
			(stroke
				(width 0.15)
				(type solid)
			)
			(layer "F.Fab")
		)
		(pad "1" smd roundrect
			(at -0.48 0 270)
			(size 0.59 0.64)
			(layers "F.Cu" "F.Mask" "F.Paste")
			(roundrect_rratio 0.25)
			(net 28 "GND")
			(pintype "passive")
		)
		(pad "2" smd roundrect
			(at 0.48 0 270)
			(size 0.59 0.64)
			(layers "F.Cu" "F.Mask" "F.Paste")
			(roundrect_rratio 0.25)
			(net 324 "/Power/1V88_VCC")
			(pintype "passive")
		)
	)
	(footprint "antmicro-footprints:R_0402_1005Metric"
		(layer "F.Cu")
		(at 111.35 93.45 90)
		(descr "Resistor SMD 0402")
		(tags "resistor SMD 0402")
		(property "Reference" "R66"
			(at 3.85 0.4 90)
			(layer "F.SilkS")
			(effects
				(font
					(size 0.7 0.7)
					(thickness 0.15)
				)
				(justify left bottom)
			)
		)
		(property "Value" "R_3k3_0402"
			(at -1.011843 1.772046 90)
			(layer "F.Fab")
			(hide yes)
			(effects
				(font
					(size 0.7 0.7)
					(thickness 0.15)
				)
				(justify left bottom)
			)
		)
		(property "Datasheet" "https://www.bourns.com/docs/product-datasheets/cr.pdf"
			(at 0 0 90)
			(layer "F.Fab")
			(hide yes)
			(effects
				(font
					(size 1.27 1.27)
					(thickness 0.15)
				)
			)
		)
		(property "Description" "SMD Chip Resistor, 3.3 kohm, ± 1%, 63 mW, 0402 [1005 Metric], Thick Film, General Purpose"
			(at 0 0 90)
			(layer "F.Fab")
			(hide yes)
			(effects
				(font
					(size 1.27 1.27)
					(thickness 0.15)
				)
			)
		)
		(property "MPN" "CR0402-FX-3301GLF"
			(at 0 0 90)
			(unlocked yes)
			(layer "F.Fab")
			(hide yes)
			(effects
				(font
					(size 1 1)
					(thickness 0.15)
				)
			)
		)
		(property "Manufacturer" "Bourns"
			(at 0 0 90)
			(unlocked yes)
			(layer "F.Fab")
			(hide yes)
			(effects
				(font
					(size 1 1)
					(thickness 0.15)
				)
			)
		)
		(property "License" "Apache-2.0"
			(at 0 0 90)
			(unlocked yes)
			(layer "F.Fab")
			(hide yes)
			(effects
				(font
					(size 1 1)
					(thickness 0.15)
				)
			)
		)
		(property "Author" "Antmicro"
			(at 0 0 90)
			(unlocked yes)
			(layer "F.Fab")
			(hide yes)
			(effects
				(font
					(size 1 1)
					(thickness 0.15)
				)
			)
		)
		(property "Val" "3k3"
			(at 0 0 90)
			(unlocked yes)
			(layer "F.Fab")
			(hide yes)
			(effects
				(font
					(size 1 1)
					(thickness 0.15)
				)
			)
		)
		(property "Tolerance" "1%"
			(at 0 0 90)
			(unlocked yes)
			(layer "F.Fab")
			(hide yes)
			(effects
				(font
					(size 1 1)
					(thickness 0.15)
				)
			)
		)
		(sheetname "/X710-AT2 10GbE/")
		(sheetfile "x710-at2-10gbe.kicad_sch")
		(attr smd)
		(fp_rect
			(start -0.925 -0.47)
			(end 0.925 0.47)
			(stroke
				(width 0.05)
				(type default)
			)
			(fill no)
			(layer "F.CrtYd")
		)
		(fp_rect
			(start -0.5 -0.25)
			(end 0.5 0.25)
			(stroke
				(width 0.15)
				(type solid)
			)
			(fill no)
			(layer "F.Fab")
		)
		(pad "1" smd roundrect
			(at -0.48 0 90)
			(size 0.59 0.64)
			(layers "F.Cu" "F.Mask" "F.Paste")
			(roundrect_rratio 0.25)
			(net 132 "/X710-AT2 10GbE/MDIO0_SDA0")
			(pintype "passive")
		)
		(pad "2" smd roundrect
			(at 0.48 0 90)
			(size 0.59 0.64)
			(layers "F.Cu" "F.Mask" "F.Paste")
			(roundrect_rratio 0.25)
			(net 7 "+3V3")
			(pintype "passive")
		)
	)
	(footprint "antmicro-footprints:R_0402_1005Metric"
		(layer "F.Cu")
		(at 73.849999 82.039995)
		(descr "Resistor SMD 0402")
		(tags "resistor SMD 0402")
		(property "Reference" "R4"
			(at -3.899999 -7.139995 0)
			(layer "F.SilkS")
			(effects
				(font
					(size 0.7 0.7)
					(thickness 0.15)
				)
				(justify left bottom)
			)
		)
		(property "Value" "R_100k_0402"
			(at -1.011843 1.772046 0)
			(layer "F.Fab")
			(hide yes)
			(effects
				(font
					(size 0.7 0.7)
					(thickness 0.15)
				)
				(justify left bottom)
			)
		)
		(property "Datasheet" "https://www.bourns.com/docs/product-datasheets/cr.pdf"
			(at 0 0 0)
			(layer "F.Fab")
			(hide yes)
			(effects
				(font
					(size 1.27 1.27)
					(thickness 0.15)
				)
			)
		)
		(property "Description" "SMD Chip Resistor, 100 kohm, ± 1%, 62.5 mW, 0402 [1005 Metric], Thick Film, General Purpose"
			(at 0 0 0)
			(layer "F.Fab")
			(hide yes)
			(effects
				(font
					(size 1.27 1.27)
					(thickness 0.15)
				)
			)
		)
		(property "MPN" "CR0402-FX-1003GLF"
			(at 0 0 0)
			(unlocked yes)
			(layer "F.Fab")
			(hide yes)
			(effects
				(font
					(size 1 1)
					(thickness 0.15)
				)
			)
		)
		(property "Manufacturer" "Bourns"
			(at 0 0 0)
			(unlocked yes)
			(layer "F.Fab")
			(hide yes)
			(effects
				(font
					(size 1 1)
					(thickness 0.15)
				)
			)
		)
		(property "License" "Apache-2.0"
			(at 0 0 0)
			(unlocked yes)
			(layer "F.Fab")
			(hide yes)
			(effects
				(font
					(size 1 1)
					(thickness 0.15)
				)
			)
		)
		(property "Author" "Antmicro"
			(at 0 0 0)
			(unlocked yes)
			(layer "F.Fab")
			(hide yes)
			(effects
				(font
					(size 1 1)
					(thickness 0.15)
				)
			)
		)
		(property "Val" "100k"
			(at 0 0 0)
			(unlocked yes)
			(layer "F.Fab")
			(hide yes)
			(effects
				(font
					(size 1 1)
					(thickness 0.15)
				)
			)
		)
		(property "Tolerance" "1%"
			(at 0 0 0)
			(unlocked yes)
			(layer "F.Fab")
			(hide yes)
			(effects
				(font
					(size 1 1)
					(thickness 0.15)
				)
			)
		)
		(sheetname "/Power/")
		(sheetfile "power.kicad_sch")
		(attr smd)
		(fp_rect
			(start -0.925 -0.47)
			(end 0.925 0.47)
			(stroke
				(width 0.05)
				(type default)
			)
			(fill no)
			(layer "F.CrtYd")
		)
		(fp_rect
			(start -0.5 -0.25)
			(end 0.5 0.25)
			(stroke
				(width 0.15)
				(type solid)
			)
			(fill no)
			(layer "F.Fab")
		)
		(pad "1" smd roundrect
			(at -0.48 0)
			(size 0.59 0.64)
			(layers "F.Cu" "F.Mask" "F.Paste")
			(roundrect_rratio 0.25)
			(net 338 "/Power/3V3_PG")
			(pintype "passive")
		)
		(pad "2" smd roundrect
			(at 0.48 0)
			(size 0.59 0.64)
			(layers "F.Cu" "F.Mask" "F.Paste")
			(roundrect_rratio 0.25)
			(net 315 "/Power/3V3_VCC")
			(pintype "passive")
		)
	)
)
